# S9S_MB_2U (Grand Teton) — schematic netlist excerpt (pin names and nets, part order shuffled) for the footprints in the layout excerpt that follows; sources: Cadence DE-HDL packaged netlist, KiCad conversion of 03242023_DA0F0TMBIJ0_F0T_Motherboard_J_brd_V01_OCP.brd

H125  HOLE  EMPTY  pkg TH  page 311 : \1\ = NC
R4626  Q_RES  0 5% CHIP  pkg 0402LF  page 248 : A = JTAG_BMC_TDO ; B = JTAG_BMC_TDO_R
R3289  Q_RES  1K 1% EMPTY  pkg 0402LF  page 166 : A = P3V3_AUX ; B = FM_P2E_SWA

(kicad_pcb
	(version 20260206)
	(generator "pcbnew")
	(generator_version "10.0")
	(general
		(thickness 1.6)
		(legacy_teardrops no)
	)
	(paper "A4")
	(title_block
		(title "03242023_DA0F0TMBIJ0_F0T_Motherboard_J_brd_V01_OCP.brd")
		(comment 1 "Grand Teton / footprints 4044-4046 of 6105")
	)
	(layers
		(0 "F.Cu" signal "TOP")
		(4 "In1.Cu" signal "GND")
		(6 "In2.Cu" signal "IN1")
		(8 "In3.Cu" signal "GND1")
		(10 "In4.Cu" signal "IN2")
		(12 "In5.Cu" signal "GND2")
		(14 "In6.Cu" signal "IN3")
		(16 "In7.Cu" signal "GND3")
		(18 "In8.Cu" signal "VCC")
		(20 "In9.Cu" signal "VCC1")
		(22 "In10.Cu" signal "GND4")
		(24 "In11.Cu" signal "IN4")
		(26 "In12.Cu" signal "GND5")
		(28 "In13.Cu" signal "IN5")
		(30 "In14.Cu" signal "GND6")
		(32 "In15.Cu" signal "IN6")
		(34 "In16.Cu" signal "GND7")
		(2 "B.Cu" signal "BOTTOM")
		(9 "F.Adhes" user "F.Adhesive")
		(11 "B.Adhes" user "B.Adhesive")
		(13 "F.Paste" user "Package Geometry/Pastemask Top")
		(15 "B.Paste" user "Package Geometry/Pastemask Bottom")
		(5 "F.SilkS" user "Ref Des/Silkscreen Top")
		(7 "B.SilkS" user "Ref Des/Silkscreen Bottom")
		(1 "F.Mask" user "Board Geometry/Soldermask Top")
		(3 "B.Mask" user "Board Geometry/Soldermask Bottom")
		(17 "Dwgs.User" user "User.Drawings")
		(19 "Cmts.User" user "User.Comments")
		(21 "Eco1.User" user "User.Eco1")
		(23 "Eco2.User" user "User.Eco2")
		(25 "Edge.Cuts" user "Board Geometry/Outline")
		(27 "Margin" user)
		(31 "F.CrtYd" user "Package Geometry/Place Bound Top")
		(29 "B.CrtYd" user "Package Geometry/Place Bound Bottom")
		(35 "F.Fab" user "Ref Des/Assembly Top")
		(33 "B.Fab" user "Ref Des/Assembly Bottom")
	)
	(footprint ""
		(layer "F.Cu")
		(at 129.159 -56.733948 180)
		(property "Reference" "R4626"
			(at 0 0 180)
			(layer "F.SilkS")
			(hide yes)
			(effects
				(font
					(size 1.27 1.27)
				)
			)
		)
		(property "Value" ""
			(at 0 0 180)
			(layer "F.Fab")
			(effects
				(font
					(size 1.27 1.27)
				)
			)
		)
		(duplicate_pad_numbers_are_jumpers no)
		(fp_line
			(start 0.7874 0.4064)
			(end -0.7874 0.4064)
			(stroke
				(width 0.1524)
				(type default)
			)
			(layer "F.SilkS")
		)
		(fp_line
			(start 0.7874 -0.4064)
			(end 0.7874 0.4064)
			(stroke
				(width 0.1524)
				(type default)
			)
			(layer "F.SilkS")
		)
		(fp_line
			(start -0.7874 0.4064)
			(end -0.7874 -0.4064)
			(stroke
				(width 0.1524)
				(type default)
			)
			(layer "F.SilkS")
		)
		(fp_line
			(start -0.7874 -0.4064)
			(end 0.7874 -0.4064)
			(stroke
				(width 0.1524)
				(type default)
			)
			(layer "F.SilkS")
		)
		(fp_line
			(start 0.67945 0.3048)
			(end 0.120396 0.3048)
			(stroke
				(width 0.1)
				(type default)
			)
			(layer "F.Fab")
		)
		(fp_line
			(start 0.67945 -0.3048)
			(end 0.67945 0.3048)
			(stroke
				(width 0.1)
				(type default)
			)
			(layer "F.Fab")
		)
		(fp_line
			(start 0.12065 -0.2794)
			(end 0.12065 -0.3048)
			(stroke
				(width 0.1)
				(type default)
			)
			(layer "F.Fab")
		)
		(fp_line
			(start 0.12065 -0.3048)
			(end 0.67945 -0.3048)
			(stroke
				(width 0.1)
				(type default)
			)
			(layer "F.Fab")
		)
		(fp_line
			(start 0.120396 0.3048)
			(end 0.120396 0.2794)
			(stroke
				(width 0.1)
				(type default)
			)
			(layer "F.Fab")
		)
		(fp_line
			(start 0.120396 0.2794)
			(end -0.12065 0.2794)
			(stroke
				(width 0.1)
				(type default)
			)
			(layer "F.Fab")
		)
		(fp_line
			(start -0.12065 0.3048)
			(end -0.67945 0.3048)
			(stroke
				(width 0.1)
				(type default)
			)
			(layer "F.Fab")
		)
		(fp_line
			(start -0.12065 0.2794)
			(end -0.12065 0.3048)
			(stroke
				(width 0.1)
				(type default)
			)
			(layer "F.Fab")
		)
		(fp_line
			(start -0.12065 -0.2794)
			(end 0.12065 -0.2794)
			(stroke
				(width 0.1)
				(type default)
			)
			(layer "F.Fab")
		)
		(fp_line
			(start -0.12065 -0.305054)
			(end -0.12065 -0.2794)
			(stroke
				(width 0.1)
				(type default)
			)
			(layer "F.Fab")
		)
		(fp_line
			(start -0.67945 0.3048)
			(end -0.67945 -0.305054)
			(stroke
				(width 0.1)
				(type default)
			)
			(layer "F.Fab")
		)
		(fp_line
			(start -0.67945 -0.305054)
			(end -0.12065 -0.305054)
			(stroke
				(width 0.1)
				(type default)
			)
			(layer "F.Fab")
		)
		(pad "1" smd circle
			(at -0.40005 0 180)
			(size 0 0)
			(layers "F.Cu" "F.Mask" "F.Paste")
			(net "JTAG_BMC_TDO")
		)
		(pad "2" smd circle
			(at 0.40005 0 180)
			(size 0 0)
			(layers "F.Cu" "F.Mask" "F.Paste")
			(net "JTAG_BMC_TDO_R")
		)
	)
	(footprint ""
		(layer "F.Cu")
		(at 9.739884 -360.76382)
		(property "Reference" "H125"
			(at -2.056384 -8.033258 0)
			(unlocked yes)
			(layer "F.SilkS")
			(effects
				(font
					(size 0.7874 0.5842)
					(thickness 0.1524)
				)
				(justify left)
			)
		)
		(property "Value" ""
			(at 0 0 0)
			(layer "F.Fab")
			(effects
				(font
					(size 1.27 1.27)
				)
			)
		)
		(duplicate_pad_numbers_are_jumpers no)
		(fp_circle
			(center 0 0)
			(end 5.8166 0)
			(stroke
				(width 0.1524)
				(type default)
			)
			(fill no)
			(layer "F.SilkS")
		)
		(fp_circle
			(center 0 0)
			(end 5.8166 0)
			(stroke
				(width 0.1524)
				(type default)
			)
			(fill no)
			(layer "B.SilkS")
		)
		(fp_circle
			(center 0 0)
			(end 5.8166 0)
			(stroke
				(width 0.1)
				(type default)
			)
			(fill no)
			(layer "B.Fab")
		)
		(fp_circle
			(center 0 0)
			(end 5.8166 0)
			(stroke
				(width 0.1)
				(type default)
			)
			(fill no)
			(layer "F.Fab")
		)
		(pad "" np_thru_hole circle
			(at 0 0)
			(size 10.0076 10.0076)
			(drill 10.0076)
			(layers "*.Cu" "*.Mask")
			(clearance 0.381)
			(thermal_gap 0.381)
		)
		(zone
			(layers "F.Cu" "B.Cu" "In1.Cu" "In2.Cu" "In3.Cu" "In4.Cu" "In5.Cu" "In6.Cu"
				"In7.Cu" "In8.Cu" "In9.Cu" "In10.Cu" "In11.Cu" "In12.Cu" "In13.Cu" "In14.Cu"
				"In15.Cu" "In16.Cu"
			)
			(hatch none 0.5)
			(connect_pads
				(clearance 0)
			)
			(min_thickness 0.25)
			(keepout
				(tracks not_allowed)
				(vias allowed)
				(pads allowed)
				(copperpour not_allowed)
				(footprints allowed)
			)
			(placement
				(enabled no)
				(sheetname "")
			)
			(fill
				(thermal_gap 0.5)
				(thermal_bridge_width 0.5)
				(island_removal_mode 0)
			)
			(polygon
				(pts
					(arc
						(start 15.251684 -360.76382)
						(mid 4.228084 -360.76382)
						(end 15.251684 -360.76382)
					)
				)
			)
		)
	)
	(footprint ""
		(layer "F.Cu")
		(at 15.436596 -390.167876)
		(property "Reference" "R3289"
			(at 0 0 0)
			(layer "F.SilkS")
			(hide yes)
			(effects
				(font
					(size 1.27 1.27)
				)
			)
		)
		(property "Value" ""
			(at 0 0 0)
			(layer "F.Fab")
			(effects
				(font
					(size 1.27 1.27)
				)
			)
		)
		(duplicate_pad_numbers_are_jumpers no)
		(fp_line
			(start -0.7874 -0.4064)
			(end 0.7874 -0.4064)
			(stroke
				(width 0.1524)
				(type default)
			)
			(layer "F.SilkS")
		)
		(fp_line
			(start -0.7874 0.4064)
			(end -0.7874 -0.4064)
			(stroke
				(width 0.1524)
				(type default)
			)
			(layer "F.SilkS")
		)
		(fp_line
			(start 0.7874 -0.4064)
			(end 0.7874 0.4064)
			(stroke
				(width 0.1524)
				(type default)
			)
			(layer "F.SilkS")
		)
		(fp_line
			(start 0.7874 0.4064)
			(end -0.7874 0.4064)
			(stroke
				(width 0.1524)
				(type default)
			)
			(layer "F.SilkS")
		)
		(fp_line
			(start -0.67945 -0.305054)
			(end -0.12065 -0.305054)
			(stroke
				(width 0.1)
				(type default)
			)
			(layer "F.Fab")
		)
		(fp_line
			(start -0.67945 0.3048)
			(end -0.67945 -0.305054)
			(stroke
				(width 0.1)
				(type default)
			)
			(layer "F.Fab")
		)
		(fp_line
			(start -0.12065 -0.305054)
			(end -0.12065 -0.2794)
			(stroke
				(width 0.1)
				(type default)
			)
			(layer "F.Fab")
		)
		(fp_line
			(start -0.12065 -0.2794)
			(end 0.12065 -0.2794)
			(stroke
				(width 0.1)
				(type default)
			)
			(layer "F.Fab")
		)
		(fp_line
			(start -0.12065 0.2794)
			(end -0.12065 0.3048)
			(stroke
				(width 0.1)
				(type default)
			)
			(layer "F.Fab")
		)
		(fp_line
			(start -0.12065 0.3048)
			(end -0.67945 0.3048)
			(stroke
				(width 0.1)
				(type default)
			)
			(layer "F.Fab")
		)
		(fp_line
			(start 0.120396 0.2794)
			(end -0.12065 0.2794)
			(stroke
				(width 0.1)
				(type default)
			)
			(layer "F.Fab")
		)
		(fp_line
			(start 0.120396 0.3048)
			(end 0.120396 0.2794)
			(stroke
				(width 0.1)
				(type default)
			)
			(layer "F.Fab")
		)
		(fp_line
			(start 0.12065 -0.3048)
			(end 0.67945 -0.3048)
			(stroke
				(width 0.1)
				(type default)
			)
			(layer "F.Fab")
		)
		(fp_line
			(start 0.12065 -0.2794)
			(end 0.12065 -0.3048)
			(stroke
				(width 0.1)
				(type default)
			)
			(layer "F.Fab")
		)
		(fp_line
			(start 0.67945 -0.3048)
			(end 0.67945 0.3048)
			(stroke
				(width 0.1)
				(type default)
			)
			(layer "F.Fab")
		)
		(fp_line
			(start 0.67945 0.3048)
			(end 0.120396 0.3048)
			(stroke
				(width 0.1)
				(type default)
			)
			(layer "F.Fab")
		)
		(pad "1" smd circle
			(at -0.40005 0)
			(size 0 0)
			(layers "F.Cu" "F.Mask" "F.Paste")
			(net "P3V3_AUX")
		)
		(pad "2" smd circle
			(at 0.40005 0)
			(size 0 0)
			(layers "F.Cu" "F.Mask" "F.Paste")
			(net "FM_P2E_SWA")
		)
	)
)
